# TIMECARD (Time Appliance Project (Time Card)) — schematic netlist excerpt (pin names and nets, part order shuffled) for the footprints in the layout excerpt that follows; sources: Cadence DE-HDL packaged netlist, KiCad conversion of R4006-B0001-02_R01.brd

Q1  POWERMOS_3P_NCH_V1  pkg SOT23_V1_H044  page 24
  G  = FT_USB_DETECT
  S  = SG
  D  = UNNAMED_524_POWERMOS3PNCHV1_I44

(kicad_pcb
	(version 20260206)
	(generator "pcbnew")
	(generator_version "10.0")
	(general
		(thickness 1.6)
		(legacy_teardrops no)
	)
	(paper "A4")
	(title_block
		(title "timecard-production-celestica-r4006 — R4006-B0001-02_R01.brd")
		(comment 1 "Time Appliance Project (Time Card) / footprints 443-443 of 1113")
	)
	(layers
		(0 "F.Cu" signal "TOP")
		(4 "In1.Cu" signal "L02_GND1")
		(6 "In2.Cu" signal "L03_SIG1")
		(8 "In3.Cu" signal "L04_GND2")
		(10 "In4.Cu" signal "L05_VCC1")
		(12 "In5.Cu" signal "L06_VCC2")
		(14 "In6.Cu" signal "L07_GND3")
		(16 "In7.Cu" signal "L08_SIG2")
		(18 "In8.Cu" signal "L09_GND4")
		(2 "B.Cu" signal "BOTTOM")
		(9 "F.Adhes" user "F.Adhesive")
		(11 "B.Adhes" user "B.Adhesive")
		(13 "F.Paste" user "Package Geometry/Pastemask Top")
		(15 "B.Paste" user "Package Geometry/Pastemask Bottom")
		(5 "F.SilkS" user "Ref Des/Silkscreen Top")
		(7 "B.SilkS" user "Ref Des/Silkscreen Bottom")
		(1 "F.Mask" user "Board Geometry/Soldermask Top")
		(3 "B.Mask" user "Board Geometry/Soldermask Bottom")
		(17 "Dwgs.User" user "User.Drawings")
		(19 "Cmts.User" user "User.Comments")
		(21 "Eco1.User" user "User.Eco1")
		(23 "Eco2.User" user "User.Eco2")
		(25 "Edge.Cuts" user "Board Geometry/Outline")
		(27 "Margin" user)
		(31 "F.CrtYd" user "Package Geometry/Place Bound Top")
		(29 "B.CrtYd" user "Package Geometry/Place Bound Bottom")
		(35 "F.Fab" user "Ref Des/Assembly Top")
		(33 "B.Fab" user "Ref Des/Assembly Bottom")
	)
	(footprint ""
		(layer "F.Cu")
		(at 112.649 -90.805)
		(property "Reference" "Q1"
			(at 2.667 -0.08763 0)
			(unlocked yes)
			(layer "F.SilkS")
			(effects
				(font
					(size 0.7874 0.5842)
					(thickness 0.1524)
				)
			)
		)
		(property "Value" ""
			(at 0 0 0)
			(layer "F.Fab")
			(effects
				(font
					(size 1.27 1.27)
				)
			)
		)
		(property "User Part Number" "PARTNUM*"
			(at -0.074676 4.841748 0)
			(unlocked yes)
			(layer "Cmts.User")
			(hide yes)
			(effects
				(font
					(size 0.7874 0.5842)
					(thickness 0.000001)
				)
			)
		)
		(property "Device Type" "POWERMOS_3P_NCH_V1-G121-10200-A"
			(at -0.051562 3.91414 0)
			(unlocked yes)
			(layer "F.Fab")
			(hide yes)
			(effects
				(font
					(size 0.7874 0.5842)
					(thickness 0.000001)
				)
			)
		)
		(duplicate_pad_numbers_are_jumpers no)
		(fp_line
			(start -1.7018 -0.9144)
			(end -0.7493 -0.9144)
			(stroke
				(width 0.1)
				(type default)
			)
			(layer "F.SilkS")
		)
		(fp_line
			(start -1.7018 2.0574)
			(end -1.7018 -0.9144)
			(stroke
				(width 0.1)
				(type default)
			)
			(layer "F.SilkS")
		)
		(fp_line
			(start -0.7493 -2.0574)
			(end 0.7493 -2.0574)
			(stroke
				(width 0.1)
				(type default)
			)
			(layer "F.SilkS")
		)
		(fp_line
			(start -0.7493 -0.9144)
			(end -0.7493 -2.0574)
			(stroke
				(width 0.1)
				(type default)
			)
			(layer "F.SilkS")
		)
		(fp_line
			(start -0.1905 0.9144)
			(end -0.1905 2.0574)
			(stroke
				(width 0.1)
				(type default)
			)
			(layer "F.SilkS")
		)
		(fp_line
			(start -0.1905 2.0574)
			(end -1.7018 2.0574)
			(stroke
				(width 0.1)
				(type default)
			)
			(layer "F.SilkS")
		)
		(fp_line
			(start 0.1905 0.9144)
			(end -0.1905 0.9144)
			(stroke
				(width 0.1)
				(type default)
			)
			(layer "F.SilkS")
		)
		(fp_line
			(start 0.1905 2.0574)
			(end 0.1905 0.9144)
			(stroke
				(width 0.1)
				(type default)
			)
			(layer "F.SilkS")
		)
		(fp_line
			(start 0.7493 -2.0574)
			(end 0.7493 -0.9144)
			(stroke
				(width 0.1)
				(type default)
			)
			(layer "F.SilkS")
		)
		(fp_line
			(start 0.7493 -0.9144)
			(end 1.7018 -0.9144)
			(stroke
				(width 0.1)
				(type default)
			)
			(layer "F.SilkS")
		)
		(fp_line
			(start 1.7018 -0.9144)
			(end 1.7018 2.0574)
			(stroke
				(width 0.1)
				(type default)
			)
			(layer "F.SilkS")
		)
		(fp_line
			(start 1.7018 2.0574)
			(end 0.1905 2.0574)
			(stroke
				(width 0.1)
				(type default)
			)
			(layer "F.SilkS")
		)
		(fp_poly
			(pts
				(arc
					(start -0.752856 2.634234)
					(mid -1.514856 2.634234)
					(end -0.752856 2.634234)
				)
			)
			(stroke
				(width 0)
				(type default)
			)
			(fill yes)
			(layer "F.SilkS")
		)
		(fp_poly
			(pts
				(xy -1.7018 2.0828) (xy -1.7018 -0.9144) (xy -0.762 -0.9144) (xy -0.762 -2.0574) (xy 0.762 -2.0574)
				(xy 0.762 -0.9144) (xy 1.7018 -0.9144) (xy 1.7018 2.0828)
			)
			(stroke
				(width 0)
				(type default)
			)
			(fill no)
			(layer "F.CrtYd")
		)
		(fp_line
			(start -1.4478 -0.6604)
			(end -1.3716 -0.5842)
			(stroke
				(width 0.1)
				(type default)
			)
			(layer "F.Fab")
		)
		(fp_line
			(start -1.4478 -0.6604)
			(end 1.4478 -0.6604)
			(stroke
				(width 0.1)
				(type default)
			)
			(layer "F.Fab")
		)
		(fp_line
			(start -1.4478 0.6604)
			(end -1.4478 -0.6604)
			(stroke
				(width 0.1)
				(type default)
			)
			(layer "F.Fab")
		)
		(fp_line
			(start -1.4478 0.6604)
			(end -1.3716 0.5842)
			(stroke
				(width 0.1)
				(type default)
			)
			(layer "F.Fab")
		)
		(fp_line
			(start -1.3716 -0.5842)
			(end 1.3716 -0.5842)
			(stroke
				(width 0.1)
				(type default)
			)
			(layer "F.Fab")
		)
		(fp_line
			(start -1.3716 0.5842)
			(end -1.3716 -0.5842)
			(stroke
				(width 0.1)
				(type default)
			)
			(layer "F.Fab")
		)
		(fp_line
			(start -1.1684 0.6604)
			(end -0.7112 0.6604)
			(stroke
				(width 0.1)
				(type default)
			)
			(layer "F.Fab")
		)
		(fp_line
			(start -1.1684 0.9144)
			(end -0.7112 0.9144)
			(stroke
				(width 0.1)
				(type default)
			)
			(layer "F.Fab")
		)
		(fp_line
			(start -1.1684 1.143)
			(end -1.1684 0.6604)
			(stroke
				(width 0.1)
				(type default)
			)
			(layer "F.Fab")
		)
		(fp_line
			(start -0.7112 0.6604)
			(end -0.7112 1.143)
			(stroke
				(width 0.1)
				(type default)
			)
			(layer "F.Fab")
		)
		(fp_line
			(start -0.7112 1.143)
			(end -1.1684 1.143)
			(stroke
				(width 0.1)
				(type default)
			)
			(layer "F.Fab")
		)
		(fp_line
			(start -0.2286 -1.143)
			(end 0.2286 -1.143)
			(stroke
				(width 0.1)
				(type default)
			)
			(layer "F.Fab")
		)
		(fp_line
			(start -0.2286 -0.9144)
			(end 0.2286 -0.9144)
			(stroke
				(width 0.1)
				(type default)
			)
			(layer "F.Fab")
		)
		(fp_line
			(start -0.2286 -0.6604)
			(end -0.2286 -1.143)
			(stroke
				(width 0.1)
				(type default)
			)
			(layer "F.Fab")
		)
		(fp_line
			(start 0.2286 -1.143)
			(end 0.2286 -0.6604)
			(stroke
				(width 0.1)
				(type default)
			)
			(layer "F.Fab")
		)
		(fp_line
			(start 0.2286 -0.6604)
			(end -0.2286 -0.6604)
			(stroke
				(width 0.1)
				(type default)
			)
			(layer "F.Fab")
		)
		(fp_line
			(start 0.7112 0.6604)
			(end 1.1684 0.6604)
			(stroke
				(width 0.1)
				(type default)
			)
			(layer "F.Fab")
		)
		(fp_line
			(start 0.7112 0.9144)
			(end 1.1684 0.9144)
			(stroke
				(width 0.1)
				(type default)
			)
			(layer "F.Fab")
		)
		(fp_line
			(start 0.7112 1.143)
			(end 0.7112 0.6604)
			(stroke
				(width 0.1)
				(type default)
			)
			(layer "F.Fab")
		)
		(fp_line
			(start 1.1684 0.6604)
			(end 1.1684 1.143)
			(stroke
				(width 0.1)
				(type default)
			)
			(layer "F.Fab")
		)
		(fp_line
			(start 1.1684 1.143)
			(end 0.7112 1.143)
			(stroke
				(width 0.1)
				(type default)
			)
			(layer "F.Fab")
		)
		(fp_line
			(start 1.3716 -0.5842)
			(end 1.3716 0.5842)
			(stroke
				(width 0.1)
				(type default)
			)
			(layer "F.Fab")
		)
		(fp_line
			(start 1.3716 -0.5842)
			(end 1.4478 -0.6604)
			(stroke
				(width 0.1)
				(type default)
			)
			(layer "F.Fab")
		)
		(fp_line
			(start 1.3716 0.5842)
			(end -1.3716 0.5842)
			(stroke
				(width 0.1)
				(type default)
			)
			(layer "F.Fab")
		)
		(fp_line
			(start 1.3716 0.5842)
			(end 1.4478 0.6604)
			(stroke
				(width 0.1)
				(type default)
			)
			(layer "F.Fab")
		)
		(fp_line
			(start 1.4478 -0.6604)
			(end 1.4478 0.6604)
			(stroke
				(width 0.1)
				(type default)
			)
			(layer "F.Fab")
		)
		(fp_line
			(start 1.4478 0.6604)
			(end -1.4478 0.6604)
			(stroke
				(width 0.1)
				(type default)
			)
			(layer "F.Fab")
		)
		(fp_poly
			(pts
				(arc
					(start -0.752856 2.634234)
					(mid -1.514856 2.634234)
					(end -0.752856 2.634234)
				)
			)
			(stroke
				(width 0)
				(type default)
			)
			(fill yes)
			(layer "F.Fab")
		)
		(fp_text user "2"
			(at 1.651 2.70637 0)
			(unlocked yes)
			(layer "F.SilkS")
			(effects
				(font
					(size 0.7874 0.5842)
					(thickness 0.1524)
				)
			)
		)
		(fp_text user "2"
			(at 0.931418 2.683764 0)
			(unlocked yes)
			(layer "F.Fab")
			(effects
				(font
					(size 0.7874 0.5842)
					(thickness 0.1524)
				)
			)
		)
		(pad "1" smd rect
			(at -0.9398 1.1049)
			(size 0.9906 1.397)
			(layers "F.Cu" "F.Mask" "F.Paste")
			(net "FT_USB_DETECT")
		)
		(pad "2" smd rect
			(at 0.9398 1.1049)
			(size 0.9906 1.397)
			(layers "F.Cu" "F.Mask" "F.Paste")
			(net "SG")
		)
		(pad "3" smd rect
			(at 0 -1.1049)
			(size 0.9906 1.397)
			(layers "F.Cu" "F.Mask" "F.Paste")
			(net "UNNAMED_524_POWERMOS3PNCHV1_I44")
		)
	)
)
